# TIMECARD (Time Appliance Project (Time Card)) — schematic netlist excerpt (pin names and nets, part order shuffled) for the footprints in the layout excerpt that follows; sources: Cadence DE-HDL packaged netlist, KiCad conversion of R4006-B0001-02_R01.brd

R133  RESISTOR  33OHM 1%  pkg SMC_0402R_H016  page 10 : \1\ = XP3R3V_FPGA ; \2\ = UNNAMED_127_G2001028301_I427_4
C130  CAPACITOR  0.1UF 10V 10%  pkg SMC_0402R_H022  page 14 : \1\ = XP3R3V_FPGA ; \2\ = SG

(kicad_pcb
	(version 20260206)
	(generator "pcbnew")
	(generator_version "10.0")
	(general
		(thickness 1.6)
		(legacy_teardrops no)
	)
	(paper "A4")
	(title_block
		(title "timecard-production-celestica-r4006 — R4006-B0001-02_R01.brd")
		(comment 1 "Time Appliance Project (Time Card) / footprints 1061-1062 of 1113")
	)
	(layers
		(0 "F.Cu" signal "TOP")
		(4 "In1.Cu" signal "L02_GND1")
		(6 "In2.Cu" signal "L03_SIG1")
		(8 "In3.Cu" signal "L04_GND2")
		(10 "In4.Cu" signal "L05_VCC1")
		(12 "In5.Cu" signal "L06_VCC2")
		(14 "In6.Cu" signal "L07_GND3")
		(16 "In7.Cu" signal "L08_SIG2")
		(18 "In8.Cu" signal "L09_GND4")
		(2 "B.Cu" signal "BOTTOM")
		(9 "F.Adhes" user "F.Adhesive")
		(11 "B.Adhes" user "B.Adhesive")
		(13 "F.Paste" user "Package Geometry/Pastemask Top")
		(15 "B.Paste" user "Package Geometry/Pastemask Bottom")
		(5 "F.SilkS" user "Ref Des/Silkscreen Top")
		(7 "B.SilkS" user "Ref Des/Silkscreen Bottom")
		(1 "F.Mask" user "Board Geometry/Soldermask Top")
		(3 "B.Mask" user "Board Geometry/Soldermask Bottom")
		(17 "Dwgs.User" user "User.Drawings")
		(19 "Cmts.User" user "User.Comments")
		(21 "Eco1.User" user "User.Eco1")
		(23 "Eco2.User" user "User.Eco2")
		(25 "Edge.Cuts" user "Board Geometry/Outline")
		(27 "Margin" user)
		(31 "F.CrtYd" user "Package Geometry/Place Bound Top")
		(29 "B.CrtYd" user "Package Geometry/Place Bound Bottom")
		(35 "F.Fab" user "Ref Des/Assembly Top")
		(33 "B.Fab" user "Ref Des/Assembly Bottom")
	)
	(footprint ""
		(layer "B.Cu")
		(at 117.347238 -49.823116 180)
		(property "Reference" "C130"
			(at 0.634238 1.834134 0)
			(unlocked yes)
			(layer "B.SilkS")
			(effects
				(font
					(size 0.635 0.4064)
					(thickness 0.1524)
				)
				(justify mirror)
			)
		)
		(property "Value" "VAL*"
			(at 0 3.718306 180)
			(unlocked yes)
			(layer "B.Fab")
			(hide yes)
			(effects
				(font
					(size 0.7874 0.5842)
					(thickness 0.127)
				)
				(justify mirror)
			)
		)
		(property "Device Type" "CAPACITOR-G105-0B104-CK,0.1UF,A"
			(at 0 1.432306 180)
			(unlocked yes)
			(layer "B.Fab")
			(hide yes)
			(effects
				(font
					(size 0.7874 0.5842)
					(thickness 0.127)
				)
				(justify mirror)
			)
		)
		(property "User Part Number" "PARTNUM*"
			(at 0 2.575306 180)
			(unlocked yes)
			(layer "Cmts.User")
			(hide yes)
			(effects
				(font
					(size 0.7874 0.5842)
					(thickness 0.127)
				)
				(justify mirror)
			)
		)
		(property "Tolerance" "TOL*"
			(at 0 4.861306 180)
			(unlocked yes)
			(layer "Cmts.User")
			(hide yes)
			(effects
				(font
					(size 0.7874 0.5842)
					(thickness 0.127)
				)
				(justify mirror)
			)
		)
		(duplicate_pad_numbers_are_jumpers no)
		(fp_line
			(start 0.970026 0.4699)
			(end 0.970026 -0.4699)
			(stroke
				(width 0.1)
				(type default)
			)
			(layer "B.SilkS")
		)
		(fp_line
			(start 0.970026 -0.4699)
			(end -0.970026 -0.4699)
			(stroke
				(width 0.1)
				(type default)
			)
			(layer "B.SilkS")
		)
		(fp_line
			(start -0.970026 0.4699)
			(end 0.970026 0.4699)
			(stroke
				(width 0.1)
				(type default)
			)
			(layer "B.SilkS")
		)
		(fp_line
			(start -0.970026 -0.4699)
			(end -0.970026 0.4699)
			(stroke
				(width 0.1)
				(type default)
			)
			(layer "B.SilkS")
		)
		(fp_poly
			(pts
				(xy 0.970026 0.4699) (xy -0.970026 0.4699) (xy -0.970026 -0.4699) (xy 0.970026 -0.4699)
			)
			(stroke
				(width 0)
				(type default)
			)
			(fill no)
			(layer "B.CrtYd")
		)
		(fp_line
			(start 0.508 0.3048)
			(end 0.508 -0.3048)
			(stroke
				(width 0.1)
				(type default)
			)
			(layer "B.Fab")
		)
		(fp_line
			(start 0.508 -0.3048)
			(end -0.508 -0.3048)
			(stroke
				(width 0.1)
				(type default)
			)
			(layer "B.Fab")
		)
		(fp_line
			(start -0.508 0.3048)
			(end 0.508 0.3048)
			(stroke
				(width 0.1)
				(type default)
			)
			(layer "B.Fab")
		)
		(fp_line
			(start -0.508 -0.3048)
			(end -0.508 0.3048)
			(stroke
				(width 0.1)
				(type default)
			)
			(layer "B.Fab")
		)
		(pad "1" smd circle
			(at 0.500126 0)
			(size 0.635 0.635)
			(layers "B.Cu" "B.Mask" "B.Paste")
			(net "XP3R3V_FPGA")
		)
		(pad "2" smd circle
			(at -0.500126 0)
			(size 0.635 0.635)
			(layers "B.Cu" "B.Mask" "B.Paste")
			(net "SG")
		)
	)
	(footprint ""
		(layer "B.Cu")
		(at 140.2842 -69.1134)
		(property "Reference" "R133"
			(at -5.0292 -0.57023 0)
			(unlocked yes)
			(layer "B.SilkS")
			(effects
				(font
					(size 0.7874 0.5842)
					(thickness 0.1524)
				)
				(justify mirror)
			)
		)
		(property "Value" "VAL*"
			(at -0.02032 2.13233 0)
			(unlocked yes)
			(layer "B.Fab")
			(hide yes)
			(effects
				(font
					(size 0.7874 0.5842)
					(thickness 0.1524)
				)
				(justify mirror)
			)
		)
		(property "Tolerance" "TOL*"
			(at -0.044704 3.05435 0)
			(unlocked yes)
			(layer "Cmts.User")
			(hide yes)
			(effects
				(font
					(size 0.7874 0.5842)
					(thickness 0.1524)
				)
				(justify mirror)
			)
		)
		(property "User Part Number" "PARTNUM*"
			(at -0.02032 4.024884 0)
			(unlocked yes)
			(layer "Cmts.User")
			(hide yes)
			(effects
				(font
					(size 0.7874 0.5842)
					(thickness 0.1524)
				)
				(justify mirror)
			)
		)
		(property "Device Type" "RESISTOR-G155-133R0-01,33OHM,1%"
			(at -0.008382 1.210564 0)
			(unlocked yes)
			(layer "B.Fab")
			(hide yes)
			(effects
				(font
					(size 0.7874 0.5842)
					(thickness 0.1524)
				)
				(justify mirror)
			)
		)
		(duplicate_pad_numbers_are_jumpers no)
		(fp_line
			(start -1.143 -0.5588)
			(end 1.143 -0.5588)
			(stroke
				(width 0.1)
				(type default)
			)
			(layer "B.SilkS")
		)
		(fp_line
			(start -1.143 0.5588)
			(end -1.143 -0.5588)
			(stroke
				(width 0.1)
				(type default)
			)
			(layer "B.SilkS")
		)
		(fp_line
			(start 1.143 -0.5588)
			(end 1.143 0.5588)
			(stroke
				(width 0.1)
				(type default)
			)
			(layer "B.SilkS")
		)
		(fp_line
			(start 1.143 0.5588)
			(end -1.143 0.5588)
			(stroke
				(width 0.1)
				(type default)
			)
			(layer "B.SilkS")
		)
		(fp_rect
			(start 1.143 0.5588)
			(end -1.143 -0.5588)
			(stroke
				(width 0)
				(type default)
			)
			(fill no)
			(layer "B.CrtYd")
		)
		(fp_line
			(start -0.508 -0.3048)
			(end 0.508 -0.3048)
			(stroke
				(width 0.1)
				(type default)
			)
			(layer "B.Fab")
		)
		(fp_line
			(start -0.508 0.3048)
			(end -0.508 -0.3048)
			(stroke
				(width 0.1)
				(type default)
			)
			(layer "B.Fab")
		)
		(fp_line
			(start 0.508 -0.3048)
			(end 0.508 0.3048)
			(stroke
				(width 0.1)
				(type default)
			)
			(layer "B.Fab")
		)
		(fp_line
			(start 0.508 0.3048)
			(end -0.508 0.3048)
			(stroke
				(width 0.1)
				(type default)
			)
			(layer "B.Fab")
		)
		(pad "1" smd rect
			(at 0.5334 0 180)
			(size 0.7112 0.6096)
			(layers "B.Cu" "B.Mask" "B.Paste")
			(net "XP3R3V_FPGA")
		)
		(pad "2" smd rect
			(at -0.5334 0 180)
			(size 0.7112 0.6096)
			(layers "B.Cu" "B.Mask" "B.Paste")
			(net "UNNAMED_127_G2001028301_I427_4")
		)
		(zone
			(layer "B.Cu")
			(hatch none 0.5)
			(connect_pads
				(clearance 0)
			)
			(min_thickness 0.25)
			(keepout
				(tracks allowed)
				(vias not_allowed)
				(pads allowed)
				(copperpour not_allowed)
				(footprints allowed)
			)
			(placement
				(enabled no)
				(sheetname "")
			)
			(fill
				(thermal_gap 0.5)
				(thermal_bridge_width 0.5)
				(island_removal_mode 0)
			)
			(polygon
				(pts
					(xy 140.3604 -68.8086) (xy 140.3604 -69.4182) (xy 140.208 -69.4182) (xy 140.208 -68.8086)
				)
			)
		)
	)
)
